# T6G (Grand Teton) — schematic parts with pin connectivity, parts 1209–1361 of 8303; source: Cadence DE-HDL packaged netlist (pstxprt.dat, pstxnet.dat, pstchip.dat)

C1549  Q_CAP_DIFFBUS  DIFF BUS_0.22UF 6.3V 20% X6S  pkg C0201  page 65 : 1 = P5E_CPU0_G3_TX_C_DP<15> ; 2 = P5E_CPU0_G3_TX_DP<15>
C1550  Q_CAP_DIFFBUS  DIFF BUS_0.22UF 6.3V 20% X6S  pkg C0201  page 65 : 1 = P5E_CPU0_G3_TX_C_DN<14> ; 2 = P5E_CPU0_G3_TX_DN<14>
C1552  Q_CAP_DIFFBUS  DIFF BUS_0.22UF 6.3V 20% X6S  pkg C0201  page 65 : 1 = P5E_CPU0_G3_TX_C_DN<13> ; 2 = P5E_CPU0_G3_TX_DN<13>
C1553  Q_CAP_DIFFBUS  DIFF BUS_0.22UF 6.3V 20% X6S  pkg C0201  page 65 : 1 = P5E_CPU0_G3_TX_C_DP<13> ; 2 = P5E_CPU0_G3_TX_DP<13>
C1554  Q_CAP  0.1UF 16V 10% X7R  pkg C0402  page 171 : 1 = P3V3_AUX ; 2 = GND
C1555  Q_CAP_DIFFBUS  DIFF BUS_0.22UF 6.3V 20% X6S  pkg C0201  page 65 : 1 = P5E_CPU0_G3_TX_C_DP<12> ; 2 = P5E_CPU0_G3_TX_DP<12>
C1556  Q_CAP_DIFFBUS  DIFF BUS_0.22UF 6.3V 20% X6S  pkg C0201  page 65 : 1 = P5E_CPU0_G3_TX_C_DN<11> ; 2 = P5E_CPU0_G3_TX_DN<11>
C1557  Q_CAP_DIFFBUS  DIFF BUS_0.22UF 6.3V 20% X6S  pkg C0201  page 65 : 1 = P5E_CPU0_G3_TX_C_DP<11> ; 2 = P5E_CPU0_G3_TX_DP<11>
C1558  Q_CAP_DIFFBUS  DIFF BUS_0.22UF 6.3V 20% X6S  pkg C0201  page 65 : 1 = P5E_CPU0_G3_TX_C_DN<10> ; 2 = P5E_CPU0_G3_TX_DN<10>
C1559  Q_CAP_DIFFBUS  DIFF BUS_0.22UF 6.3V 20% X6S  pkg C0201  page 65 : 1 = P5E_CPU0_G3_TX_C_DP<10> ; 2 = P5E_CPU0_G3_TX_DP<10>
C1560  Q_CAP_DIFFBUS  DIFF BUS_0.22UF 6.3V 20% X6S  pkg C0201  page 65 : 1 = P5E_CPU0_G3_TX_C_DN<9> ; 2 = P5E_CPU0_G3_TX_DN<9>
C1561  Q_CAP  0.1UF 25V 10% EMPTY  pkg 0402  page 268 : 1 = U206_VS ; 2 = GND
C1563  Q_CAP  0.1UF 16V 10% X7R  pkg C0402  page 187 : 1 = CLR_CMOS ; 2 = GND
C1564  Q_CAP  1UF 25V 10% X6S  pkg C0402  page 187 : 1 = P1V5_BAT_OUT ; 2 = GND
C1565  Q_CAP_DIFFBUS  DIFF BUS_0.22UF 6.3V 20% X6S  pkg C0201  page 65 : 1 = P5E_CPU0_G3_TX_C_DP<7> ; 2 = P5E_CPU0_G3_TX_DP<7>
C1566  Q_CAP_DIFFBUS  DIFF BUS_0.22UF 6.3V 20% X6S  pkg C0201  page 65 : 1 = P5E_CPU0_G3_TX_C_DN<6> ; 2 = P5E_CPU0_G3_TX_DN<6>
C1567  Q_CAP  1UF 25V 10% X6S  pkg C0402  page 187 : 1 = P1V5_BAT ; 2 = GND
C1568  Q_CAP_DIFFBUS  DIFF BUS_0.22UF 6.3V 20% X6S  pkg C0201  page 65 : 1 = P5E_CPU0_G3_TX_C_DN<5> ; 2 = P5E_CPU0_G3_TX_DN<5>
C1569  Q_CAP_DIFFBUS  DIFF BUS_0.22UF 6.3V 20% X6S  pkg C0201  page 65 : 1 = P5E_CPU0_G3_TX_C_DP<5> ; 2 = P5E_CPU0_G3_TX_DP<5>
C1570  Q_CAP_DIFFBUS  DIFF BUS_0.22UF 6.3V 20% X6S  pkg C0201  page 65 : 1 = P5E_CPU0_G3_TX_C_DN<4> ; 2 = P5E_CPU0_G3_TX_DN<4>
C1571  Q_CAP_DIFFBUS  DIFF BUS_0.22UF 6.3V 20% X6S  pkg C0201  page 65 : 1 = P5E_CPU0_G3_TX_C_DP<4> ; 2 = P5E_CPU0_G3_TX_DP<4>
C1572  Q_CAP_DIFFBUS  DIFF BUS_0.22UF 6.3V 20% X6S  pkg C0201  page 65 : 1 = P5E_CPU0_G3_TX_C_DN<3> ; 2 = P5E_CPU0_G3_TX_DN<3>
C1573  Q_CAP_DIFFBUS  DIFF BUS_0.22UF 6.3V 20% X6S  pkg C0201  page 65 : 1 = P5E_CPU0_G3_TX_C_DP<3> ; 2 = P5E_CPU0_G3_TX_DP<3>
C1574  Q_CAP_DIFFBUS  DIFF BUS_0.22UF 6.3V 20% X6S  pkg C0201  page 65 : 1 = P5E_CPU0_G3_TX_C_DN<2> ; 2 = P5E_CPU0_G3_TX_DN<2>
C1575  Q_CAP_DIFFBUS  DIFF BUS_0.22UF 6.3V 20% X6S  pkg C0201  page 65 : 1 = P5E_CPU0_G3_TX_C_DP<2> ; 2 = P5E_CPU0_G3_TX_DP<2>
C1576  Q_CAP_DIFFBUS  DIFF BUS_0.22UF 6.3V 20% X6S  pkg C0201  page 65 : 1 = P5E_CPU0_G3_TX_C_DN<1> ; 2 = P5E_CPU0_G3_TX_DN<1>
C1577  Q_CAP_DIFFBUS  DIFF BUS_0.22UF 6.3V 20% X6S  pkg C0201  page 65 : 1 = P5E_CPU0_G3_TX_C_DP<1> ; 2 = P5E_CPU0_G3_TX_DP<1>
C1578  Q_CAP_DIFFBUS  DIFF BUS_0.22UF 6.3V 20% X6S  pkg C0201  page 65 : 1 = P5E_CPU0_G3_TX_C_DN<0> ; 2 = P5E_CPU0_G3_TX_DN<0>
C1579  Q_CAP_DIFFBUS  DIFF BUS_0.22UF 6.3V 20% X6S  pkg C0201  page 65 : 1 = P5E_CPU0_G3_TX_C_DP<0> ; 2 = P5E_CPU0_G3_TX_DP<0>
C1592  Q_CAP  0.1UF 25V 10% X7R  pkg 0402  page 145 : 1 = P3V3_AUX ; 2 = GND
C1663  Q_CAP  0.1UF 25V 10% X7R  pkg 0402  page 133 : 1 = P3V3_AUX ; 2 = GND
C1707  Q_CAP  0.1UF 25V 10% X7R  pkg 0402  page 248 : 1 = P3V3_AUX ; 2 = GND
C1708  Q_CAP  0.1UF 25V 10% X7R  pkg 0402  page 248 : 1 = P3V3_AUX ; 2 = GND
C1713  Q_CAP  0.1UF 25V 10% X7R  pkg 0402  page 245 : 1 = P3V3_AUX ; 2 = GND
C1751  Q_CAP  0.1UF 25V 10% X7R  pkg 0402  page 240 : 1 = P3V3_AUX ; 2 = GND
C1754  Q_CAP  0.1UF 25V 10% X7R  pkg 0402  page 127 : 1 = FM_SWB_BIC_READY_ISO_N ; 2 = GND
C1756  Q_CAP  0.1UF 25V 10% X7R  pkg 0402  page 127 : 1 = FM_GPU_PWRGD_ISO ; 2 = GND
C1757  Q_CAP  0.1UF 25V 10% X7R  pkg 0402  page 257 : 1 = P3V3_MAX11617_VDD ; 2 = GND
C1766  Q_CAP  0.1UF 25V 10% X7R  pkg 0402  page 248 : 1 = P3V3_AUX ; 2 = GND
C1767  Q_CAP  10UF 16V 10% X6S  pkg C0805  page 257 : 1 = MAX11617_VREF ; 2 = GND
C1768  Q_CAP  10UF 16V 10% X6S  pkg C0805  page 257 : 1 = P3V3_MAX11617_VDD ; 2 = GND
C1769  Q_CAP  0.1UF 25V 10% X7R  pkg 0402  page 130 : 1 = P3V3_AUX ; 2 = GND
C1770  Q_CAP  0.1UF 25V 10% X7R  pkg 0402  page 130 : 1 = P3V3_AUX ; 2 = GND
C1772  Q_CAP  0.1UF 25V 10% X7R  pkg 0402  page 127 : 1 = RST_BMC_FROM_SWB_ISO_N ; 2 = GND
C1773  Q_CAP  0.1UF 25V 10% X7R  pkg 0402  page 127 : 1 = BIC_MONITER_ISO ; 2 = GND
C1774  Q_CAP  0.1UF 25V 10% X7R  pkg 0402  page 127 : 1 = FM_SWB_PWRGD_ISO ; 2 = GND
C1775  Q_CAP  0.1UF 25V 10% X7R  pkg 0402  page 241 : 1 = P3V3_AUX ; 2 = GND
C1786  Q_CAP  1000PF 50V 10% X7R  pkg 0603  page 267 : 1 = P12V_HSC_TEMP_D+ ; 2 = P12V_HSC_TEMP_D-
C1787  Q_CAP  0.1UF 16V 10% X7R  pkg C0402  page 267 : 1 = P3V3_AUX ; 2 = GND
C1792  Q_CAP_DIFFBUS  DIFF BUS_0.22UF 6.3V 20% X6S  pkg C0201  page 65 : 1 = P5E_CPU0_G3_TX_C_DP<14> ; 2 = P5E_CPU0_G3_TX_DP<14>
C1793  Q_CAP_DIFFBUS  DIFF BUS_0.22UF 6.3V 20% X6S  pkg C0201  page 65 : 1 = P5E_CPU0_G3_TX_C_DP<9> ; 2 = P5E_CPU0_G3_TX_DP<9>
C1794  Q_CAP_DIFFBUS  DIFF BUS_0.22UF 6.3V 20% X6S  pkg C0201  page 65 : 1 = P5E_CPU0_G3_TX_C_DN<8> ; 2 = P5E_CPU0_G3_TX_DN<8>
C1796  Q_CAP  0.1UF 25V 10% X7R  pkg 0402  page 248 : 1 = P3V3_AUX ; 2 = GND
C1797  Q_CAP  0.1UF 25V 10% X7R  pkg 0402  page 268 : 1 = PDB_PRSNT_R_N ; 2 = GND
C1802  Q_CAP  0.1UF 25V 10% X7R  pkg 0402  page 127 : 1 = FM_SMB_1_ALERT_GPU_ISO_N ; 2 = GND
C1803  Q_CAP  0.1UF 25V 10% X7R  pkg 0402  page 130 : 1 = P3V3_AUX ; 2 = GND
C1804  Q_CAP  0.1UF 25V 10% X7R  pkg 0402  page 127 : 1 = FM_SMB_2_ALERT_GPU_ISO_N ; 2 = GND
C1809  Q_CAP  0.1UF 25V 10% X7R  pkg 0402  page 140 : 1 = P3V3_AUX ; 2 = GND
C1810  Q_CAP  0.1UF 25V 10% X7R  pkg 0402  page 140 : 1 = P3V3_AUX ; 2 = GND
C1821  Q_CAP  0.1UF 25V 10% X7R  pkg 0402  page 139 : 1 = P3V3_AUX ; 2 = GND
C1822  Q_CAP  0.1UF 25V 10% X7R  pkg 0402  page 139 : 1 = P3V3_AUX ; 2 = GND
C1823  Q_CAP  0.1UF 25V 10% X7R  pkg 0402  page 139 : 1 = P3V3_AUX ; 2 = GND
C1824  Q_CAP  0.1UF 25V 10% X7R  pkg 0402  page 139 : 1 = P3V3_AUX ; 2 = GND
C1825  Q_CAP  0.1UF 25V 10% X7R  pkg 0402  page 138 : 1 = P3V3_AUX ; 2 = GND
C1826  Q_CAP  0.1UF 25V 10% X7R  pkg 0402  page 138 : 1 = P3V3_AUX ; 2 = GND
C1827  Q_CAP  0.1UF 25V 10% X7R  pkg 0402  page 138 : 1 = P3V3_AUX ; 2 = GND
C1829  Q_CAP  22UF 16V 20% X6S  pkg C0805  page 137 : 1 = P12V_OCP_V3_2_R ; 2 = GND
C1830  Q_CAP  22UF 16V 20% X6S  pkg C0805  page 137 : 1 = P12V_OCP_V3_2_R ; 2 = GND
C1831  Q_CAP  0.1UF 25V 10% X7R  pkg 0402  page 137 : 1 = P12V_OCP_V3_2_R ; 2 = GND
C1832  Q_CAP  0.1UF 25V 10% X7R  pkg 0402  page 137 : 1 = P12V_OCP_V3_2_R ; 2 = GND
C1833  Q_CAP  0.1UF 25V 10% X7R  pkg 0402  page 137 : 1 = P12V_OCP_V3_2_R ; 2 = GND
C1834  Q_CAP  0.1UF 25V 10% X7R  pkg 0402  page 137 : 1 = P12V_OCP_V3_2_R ; 2 = GND
C1835  Q_CAP  0.1UF 25V 10% X7R  pkg 0402  page 137 : 1 = P3V3_OCP_V3_2 ; 2 = GND
C1836  Q_CAP  0.1UF 25V 10% X7R  pkg 0402  page 137 : 1 = P3V3_OCP_V3_2 ; 2 = GND
C1837  Q_CAP  0.1UF 25V 10% X7R  pkg 0402  page 137 : 1 = P3V3_OCP_V3_2 ; 2 = GND
C1838  Q_CAP  0.1UF 25V 10% X7R  pkg 0402  page 137 : 1 = P3V3_OCP_V3_2 ; 2 = GND
C1839  Q_CAP  0.1UF 25V 10% X7R  pkg 0402  page 137 : 1 = P12V_OCP_V3_2_R ; 2 = GND
C1840  Q_CAP  0.1UF 25V 10% X7R  pkg 0402  page 132 : 1 = P3V3_AUX ; 2 = GND
C1841  Q_CAP  0.1UF 25V 10% X7R  pkg 0402  page 139 : 1 = P3V3_AUX ; 2 = GND
C1859  Q_CAP  0.1UF 25V 10% X7R  pkg 0402  page 247 : 1 = P3V3_AUX ; 2 = GND
C1860  Q_CAP  0.1UF 25V 10% X7R  pkg 0402  page 247 : 1 = P3V3_AUX ; 2 = GND
C1861  Q_CAP  0.1UF 25V 10% X7R  pkg 0402  page 247 : 1 = P3V3_OCP_V3_2 ; 2 = GND
C1862  Q_CAP  0.1UF 25V 10% X7R  pkg 0402  page 247 : 1 = P3V3_OCP_SFF ; 2 = GND
C1863  Q_CAP  0.1UF 25V 10% X7R  pkg 0402  page 111 : 1 = P3V3_AUX ; 2 = GND
C1864  Q_CAP  0.1UF 25V 10% X7R  pkg 0402  page 111 : 1 = P3V3_AUX ; 2 = GND
C1865  Q_CAP  0.1UF 25V 10% X7R  pkg 0402  page 111 : 1 = P3V3_AUX ; 2 = GND
C1866  Q_CAP  0.1UF 25V 10% X7R  pkg 0402  page 111 : 1 = P3V3_AUX ; 2 = GND
C1867  Q_CAP  10UF 25V 10% X6S  pkg C0805  page 111 : 1 = P3V3_AUX ; 2 = GND
C1868  Q_CAP  0.1UF 25V 10% X7R  pkg 0402  page 113 : 1 = P2E_MB_BMC_RX_BUF_C_DP<0> ; 2 = P2E_MB_BMC_RX_BUF_DP<0>
C1869  Q_CAP  0.1UF 25V 10% X7R  pkg 0402  page 113 : 1 = P2E_MB_BMC_RX_BUF_C_DN<0> ; 2 = P2E_MB_BMC_RX_BUF_DN<0>
C1870  Q_CAP  0.1UF 25V 10% X7R  pkg 0402  page 113 : 1 = P2E_MB_BMC_TX_BUF_DP<0> ; 2 = P2E_MB_BMC_TX_BUF_C_DP<0>
C1871  Q_CAP  0.1UF 25V 10% X7R  pkg 0402  page 113 : 1 = P2E_MB_BMC_TX_BUF_DN<0> ; 2 = P2E_MB_BMC_TX_BUF_C_DN<0>
C1873  Q_CAP  0.1UF 25V 10% X7R  pkg 0402  page 144 : 1 = P3V3_AUX ; 2 = GND
C1874  Q_CAP  0.1UF 25V 10% X7R  pkg 0402  page 143 : 1 = P3V3_AUX ; 2 = GND
C1875  Q_CAP  0.1UF 25V 10% X7R  pkg 0402  page 143 : 1 = P3V3_AUX ; 2 = GND
C1876  Q_CAP  0.1UF 25V 10% X7R  pkg 0402  page 143 : 1 = P3V3_AUX ; 2 = GND
C1877  Q_CAP  0.1UF 25V 10% X7R  pkg 0402  page 143 : 1 = P3V3_AUX ; 2 = GND
C1878  Q_CAP  0.1UF 25V 10% X7R  pkg 0402  page 143 : 1 = P3V3_AUX ; 2 = GND
C1879  Q_CAP  0.1UF 25V 10% X7R  pkg 0402  page 143 : 1 = P3V3_AUX ; 2 = GND
C1880  Q_CAP  0.1UF 25V 10% X7R  pkg 0402  page 143 : 1 = P3V3_AUX ; 2 = GND
C1881  Q_CAP  0.1UF 25V 10% X7R  pkg 0402  page 127 : 1 = GPU_FPGA_READY_ISO ; 2 = GND
C1882  Q_CAP  0.1UF 25V 10% X7R  pkg 0402  page 233 : 1 = P3V3_AUX ; 2 = GND
C1883  Q_CAP  10UF 25V 10% X6S  pkg C0805  page 233 : 1 = VFG3P3_CLK_GEN ; 2 = GND
C1884  Q_CAP  1UF 25V 10% X6S  pkg C0402  page 233 : 1 = VFG_3P3A_CLK_GEN ; 2 = GND
C1886  Q_CAP  0.1UF 25V 10% X7R  pkg 0402  page 233 : 1 = VFG3P3_CLK_GEN ; 2 = GND
C1889  Q_CAP  0.1UF 25V 10% X7R  pkg 0402  page 233 : 1 = VFG3P3_CLK_GEN ; 2 = GND
C1920  Q_CAP  22UF 6.3V 20% X6S  pkg C0603  page 144 : 1 = P3V3_M2_0 ; 2 = GND
C1921  Q_CAP  22UF 6.3V 20% X6S  pkg C0603  page 144 : 1 = P3V3_M2_0 ; 2 = GND
C1922  Q_CAP  22UF 4V 20% X6S  pkg C0402  page 69 : 1 = PVDDCR_CPU0_P0 ; 2 = GND
C1923  Q_CAP  0.1UF 25V 10% X7R  pkg 0402  page 144 : 1 = P3V3_M2_0 ; 2 = GND
C1924  Q_CAP  0.1UF 25V 10% X7R  pkg 0402  page 144 : 1 = P3V3_M2_0 ; 2 = GND
C1925  Q_CAP  0.1UF 25V 10% X7R  pkg 0402  page 144 : 1 = P3V3_M2_0 ; 2 = GND
C1957  Q_CAP  0.1UF 25V 10% X7R  pkg 0402  page 128 : 1 = P3V3_AUX ; 2 = GND
C1958  Q_CAP  0.1UF 25V 10% X7R  pkg 0402  page 128 : 1 = P3V3_AUX ; 2 = GND
C1963  Q_CAP  0.1UF 25V 10% X7R  pkg 0402  page 129 : 1 = P3V3_AUX ; 2 = GND
C1973  Q_CAP  0.1UF 25V 10% X7R  pkg 0402  page 126 : 1 = GPU_BASE_HMC_READY_ISO ; 2 = GND
C1974  Q_CAP  0.1UF 25V 10% X7R  pkg 0402  page 126 : 1 = GPU_FPGA_THERM_OVERT_ISO_N ; 2 = GND
C1975  Q_CAP  0.1UF 25V 10% X7R  pkg 0402  page 126 : 1 = GPU_HMC_PRSNT_ISO_N ; 2 = GND
C1976  Q_CAP  0.1UF 25V 10% X7R  pkg 0402  page 126 : 1 = GPU_FPGA_OVERT_ISO_N ; 2 = GND
C1977  Q_CAP  0.1UF 25V 10% X7R  pkg 0402  page 128 : 1 = P3V3_AUX ; 2 = GND
C1978  Q_CAP  0.1UF 25V 10% X7R  pkg 0402  page 126 : 1 = GPU_PRSNT_N_ISO ; 2 = GND
C1979  Q_CAP  0.1UF 25V 10% X7R  pkg 0402  page 129 : 1 = P3V3_AUX ; 2 = GND
C1988  Q_CAP  0.1UF 25V 10% X7R  pkg 0402  page 126 : 1 = GPU_FPGA_EROT_FATALERR_ISO_N ; 2 = GND
C1989  Q_CAP_DIFFBUS  DIFF BUS_0.22UF 6.3V 20% X6S  pkg C0201  page 67 : 1 = P3E_CPU0_P4_TX_C_DP<3> ; 2 = P3E_CPU0_P4_TX_DP<3>
C1990  Q_CAP_DIFFBUS  DIFF BUS_0.22UF 6.3V 20% X6S  pkg C0201  page 67 : 1 = P3E_CPU0_P4_TX_C_DN<3> ; 2 = P3E_CPU0_P4_TX_DN<3>
C1991  Q_CAP_DIFFBUS  DIFF BUS_0.22UF 6.3V 20% X6S  pkg C0201  page 67 : 1 = P3E_CPU0_P4_TX_C_DP<2> ; 2 = P3E_CPU0_P4_TX_DP<2>
C1992  Q_CAP_DIFFBUS  DIFF BUS_0.22UF 6.3V 20% X6S  pkg C0201  page 67 : 1 = P3E_CPU0_P4_TX_C_DN<2> ; 2 = P3E_CPU0_P4_TX_DN<2>
C1993  Q_CAP_DIFFBUS  DIFF BUS_0.22UF 6.3V 20% X6S  pkg C0201  page 67 : 1 = P3E_CPU0_P4_TX_C_DP<1> ; 2 = P3E_CPU0_P4_TX_DP<1>
C1994  Q_CAP_DIFFBUS  DIFF BUS_0.22UF 6.3V 20% X6S  pkg C0201  page 67 : 1 = P3E_CPU0_P4_TX_C_DN<1> ; 2 = P3E_CPU0_P4_TX_DN<1>
C1995  Q_CAP_DIFFBUS  DIFF BUS_0.22UF 6.3V 20% X6S  pkg C0201  page 67 : 1 = P3E_CPU0_P4_TX_C_DP<0> ; 2 = P3E_CPU0_P4_TX_DP<0>
C1996  Q_CAP_DIFFBUS  DIFF BUS_0.22UF 6.3V 20% X6S  pkg C0201  page 67 : 1 = P3E_CPU0_P4_TX_C_DN<0> ; 2 = P3E_CPU0_P4_TX_DN<0>
C1997  Q_CAP  0.1UF 25V 10% X7R  pkg 0402  page 148 : 1 = P3V3_AUX ; 2 = GND
C1998  Q_CAP  0.1UF 25V 10% X7R  pkg 0402  page 148 : 1 = P3V3_E1S_0 ; 2 = GND
C2007  Q_CAP  1UF 25V 10% X6S  pkg C0402  page 144 : 1 = P3V3_AUX ; 2 = GND
C2010  Q_CAP  0.1UF 25V 10% X7R  pkg 0402  page 235 : 1 = P3V3_AUX ; 2 = GND
C2012  Q_CAP  0.1UF 25V 10% X7R  pkg 0402  page 237 : 1 = P3V3_AUX ; 2 = GND
C2013  Q_CAP  0.1UF 25V 10% X7R  pkg 0402  page 237 : 1 = P3V3_AUX ; 2 = GND
C2014  Q_CAP  0.1UF 25V 10% X7R  pkg 0402  page 237 : 1 = P3V3_AUX ; 2 = GND
C2015  Q_CAP  0.1UF 25V 10% X7R  pkg 0402  page 236 : 1 = P3V3_AUX ; 2 = GND
C2017  Q_CAP  0.1UF 25V 10% X7R  pkg 0402  page 237 : 1 = P3V3_OCP_V3_2_R ; 2 = GND
C2018  Q_CAP  0.1UF 25V 10% X7R  pkg 0402  page 237 : 1 = P3V3 ; 2 = GND
C2019  Q_CAP  0.1UF 25V 10% X7R  pkg 0402  page 237 : 1 = P12V_SCM_R ; 2 = GND
C2020  Q_CAP  0.1UF 25V 10% X7R  pkg 0402  page 237 : 1 = VSENSE_P12V_INA230_3_INP ; 2 = VSENSE_P12V_INA230_3_INN
C2021  Q_CAP  0.1UF 25V 10% X7R  pkg 0402  page 237 : 1 = VSENSE_P12V_INA230_4_INP ; 2 = VSENSE_P12V_INA230_4_INN
C2022  Q_CAP  0.1UF 25V 10% X7R  pkg 0402  page 237 : 1 = VSENSE_P12V_INA230_5_INP ; 2 = VSENSE_P12V_INA230_5_INN
C2024  Q_CAP  0.1UF 25V 10% X7R  pkg 0402  page 236 : 1 = P3V3_OCP_SFF_R ; 2 = GND
C2027  Q_CAP  0.1UF 25V 10% X7R  pkg 0402  page 236 : 1 = VSENSE_P3V3_INA230_1_INP ; 2 = VSENSE_P3V3_INA230_1_INN
C2029  Q_CAP  15PF 50V 5% C0G  pkg 0402  page 234 : 1 = USB_HUB_XTAL_IN ; 2 = GND
C2030  Q_CAP  15PF 50V 5% C0G  pkg 0402  page 234 : 1 = USB_HUB_XTAL_OUT ; 2 = GND
C2031  Q_CAP  1UF 25V 10% X6S  pkg C0402  page 234 : 1 = P3V3_AUX_USB_HUB ; 2 = GND
C2032  Q_CAP  0.1UF 25V 10% X7R  pkg 0402  page 234 : 1 = P3V3_AUX_USB_HUB ; 2 = GND
C2033  Q_CAP  0.1UF 25V 10% X7R  pkg 0402  page 234 : 1 = P3V3_AUX_USB_HUB ; 2 = GND
C2034  Q_CAP  0.1UF 25V 10% X7R  pkg 0402  page 234 : 1 = P3V3_AUX_USB_HUB ; 2 = GND
